# T6G (Grand Teton) — schematic netlist excerpt (pin names and nets, part order shuffled) for the footprints in the layout excerpt that follows; sources: Cadence DE-HDL packaged netlist, KiCad conversion of 04192023_DAF0TMB3IC0_F0TG_MB_C_brd_V02_OCP.brd

R417  Q_RES  2.2K 5% CHIP  pkg 0402LF  page 27 : A = CPU0_THERMTRIP_N ; B = PVDD18_S5_P0

U29  SN74LVC2G07DCKR  IC  pkg SMLF  page 78
  \1a\  = PWRGD_CPU0_PWROK
  GND  = GND
  \2a\  = PWRGD_CPU0_PWROK
  \2y\  = PVDDCR_CPU1_P0_RESET_N
  VCC  = P1V8_AUX
  \1y\  = PVDDCR_CPU0_P0_RESET_N

(kicad_pcb
	(version 20260206)
	(generator "pcbnew")
	(generator_version "10.0")
	(general
		(thickness 1.6)
		(legacy_teardrops no)
	)
	(paper "A4")
	(title_block
		(title "04192023_DAF0TMB3IC0_F0TG_MB_C_brd_V02_OCP.brd")
		(comment 1 "Grand Teton / footprints 381-382 of 8354")
	)
	(layers
		(0 "F.Cu" signal "TOP")
		(4 "In1.Cu" signal "GND")
		(6 "In2.Cu" signal "IN1")
		(8 "In3.Cu" signal "GND1")
		(10 "In4.Cu" signal "IN2")
		(12 "In5.Cu" signal "GND2")
		(14 "In6.Cu" signal "IN3")
		(16 "In7.Cu" signal "GND3")
		(18 "In8.Cu" signal "VCC")
		(20 "In9.Cu" signal "VCC1")
		(22 "In10.Cu" signal "GND4")
		(24 "In11.Cu" signal "IN4")
		(26 "In12.Cu" signal "GND5")
		(28 "In13.Cu" signal "IN5")
		(30 "In14.Cu" signal "GND6")
		(32 "In15.Cu" signal "IN6")
		(34 "In16.Cu" signal "GND7")
		(2 "B.Cu" signal "BOTTOM")
		(9 "F.Adhes" user "F.Adhesive")
		(11 "B.Adhes" user "B.Adhesive")
		(13 "F.Paste" user "Package Geometry/Pastemask Top")
		(15 "B.Paste" user "Package Geometry/Pastemask Bottom")
		(5 "F.SilkS" user "Ref Des/Silkscreen Top")
		(7 "B.SilkS" user "Ref Des/Silkscreen Bottom")
		(1 "F.Mask" user "Board Geometry/Soldermask Top")
		(3 "B.Mask" user "Board Geometry/Soldermask Bottom")
		(17 "Dwgs.User" user "User.Drawings")
		(19 "Cmts.User" user "User.Comments")
		(21 "Eco1.User" user "User.Eco1")
		(23 "Eco2.User" user "User.Eco2")
		(25 "Edge.Cuts" user "Board Geometry/Outline")
		(27 "Margin" user)
		(31 "F.CrtYd" user "Package Geometry/Place Bound Top")
		(29 "B.CrtYd" user "Package Geometry/Place Bound Bottom")
		(35 "F.Fab" user "Ref Des/Assembly Top")
		(33 "B.Fab" user "Ref Des/Assembly Bottom")
	)
	(footprint ""
		(layer "F.Cu")
		(at 391.83945 -140.024612 90)
		(property "Reference" "U29"
			(at 0.762 2.00787 90)
			(unlocked yes)
			(layer "F.SilkS")
			(effects
				(font
					(size 0.7874 0.5842)
					(thickness 0.1524)
				)
			)
		)
		(property "Value" ""
			(at 0 0 90)
			(layer "F.Fab")
			(effects
				(font
					(size 1.27 1.27)
				)
			)
		)
		(duplicate_pad_numbers_are_jumpers no)
		(fp_line
			(start 1.7272 -1.1176)
			(end 0.254 -1.1176)
			(stroke
				(width 0.1524)
				(type default)
			)
			(layer "F.SilkS")
		)
		(fp_line
			(start 1.7272 -1.1176)
			(end 1.7272 1.1176)
			(stroke
				(width 0.1524)
				(type default)
			)
			(layer "F.SilkS")
		)
		(fp_line
			(start 0.254 -1.1176)
			(end 0 -0.7366)
			(stroke
				(width 0.1524)
				(type default)
			)
			(layer "F.SilkS")
		)
		(fp_line
			(start -0.254 -1.1176)
			(end -1.7272 -1.1176)
			(stroke
				(width 0.1524)
				(type default)
			)
			(layer "F.SilkS")
		)
		(fp_line
			(start 0 -0.7366)
			(end -0.254 -1.1176)
			(stroke
				(width 0.1524)
				(type default)
			)
			(layer "F.SilkS")
		)
		(fp_line
			(start 1.7272 1.1176)
			(end -1.7272 1.1176)
			(stroke
				(width 0.1524)
				(type default)
			)
			(layer "F.SilkS")
		)
		(fp_line
			(start -1.7272 1.1176)
			(end -1.7272 -1.1176)
			(stroke
				(width 0.1524)
				(type default)
			)
			(layer "F.SilkS")
		)
		(fp_poly
			(pts
				(xy -0.735076 -2.056638) (xy -1.116076 -1.294638) (xy -1.497076 -2.056638)
			)
			(stroke
				(width 0)
				(type default)
			)
			(fill yes)
			(layer "F.SilkS")
		)
		(fp_line
			(start 1.5748 -1.1176)
			(end -1.5748 -1.1176)
			(stroke
				(width 0.1)
				(type default)
			)
			(layer "F.Fab")
		)
		(fp_line
			(start -1.5748 -1.1176)
			(end -1.5748 1.1176)
			(stroke
				(width 0.1)
				(type default)
			)
			(layer "F.Fab")
		)
		(fp_line
			(start 1.5748 1.1176)
			(end 1.5748 -1.1176)
			(stroke
				(width 0.1)
				(type default)
			)
			(layer "F.Fab")
		)
		(fp_line
			(start -1.5748 1.1176)
			(end 1.5748 1.1176)
			(stroke
				(width 0.1)
				(type default)
			)
			(layer "F.Fab")
		)
		(fp_poly
			(pts
				(xy -1.9558 -0.649986) (xy -2.7178 -0.268986) (xy -2.7178 -1.030986)
			)
			(stroke
				(width 0)
				(type default)
			)
			(fill yes)
			(layer "F.Fab")
		)
		(pad "1" smd rect
			(at -0.999998 -0.649986)
			(size 0.3556 1.1176)
			(layers "F.Cu" "F.Mask" "F.Paste")
			(net "PWRGD_CPU0_PWROK")
		)
		(pad "2" smd rect
			(at -0.999998 0)
			(size 0.3556 1.1176)
			(layers "F.Cu" "F.Mask" "F.Paste")
			(net "GND")
		)
		(pad "3" smd rect
			(at -0.999998 0.649986)
			(size 0.3556 1.1176)
			(layers "F.Cu" "F.Mask" "F.Paste")
			(net "PWRGD_CPU0_PWROK")
		)
		(pad "4" smd rect
			(at 0.999998 0.649986)
			(size 0.3556 1.1176)
			(layers "F.Cu" "F.Mask" "F.Paste")
			(net "PVDDCR_CPU1_P0_RESET_N")
		)
		(pad "5" smd rect
			(at 0.999998 0)
			(size 0.3556 1.1176)
			(layers "F.Cu" "F.Mask" "F.Paste")
			(net "P1V8_AUX")
		)
		(pad "6" smd rect
			(at 0.999998 -0.649986)
			(size 0.3556 1.1176)
			(layers "F.Cu" "F.Mask" "F.Paste")
			(net "PVDDCR_CPU0_P0_RESET_N")
		)
	)
	(footprint ""
		(layer "F.Cu")
		(at 396.279878 -321.148202 90)
		(property "Reference" "R417"
			(at 0 0 90)
			(layer "F.SilkS")
			(hide yes)
			(effects
				(font
					(size 1.27 1.27)
				)
			)
		)
		(property "Value" ""
			(at 0 0 90)
			(layer "F.Fab")
			(effects
				(font
					(size 1.27 1.27)
				)
			)
		)
		(duplicate_pad_numbers_are_jumpers no)
		(fp_line
			(start 0.7874 -0.4064)
			(end 0.7874 0.4064)
			(stroke
				(width 0.1524)
				(type default)
			)
			(layer "F.SilkS")
		)
		(fp_line
			(start -0.7874 -0.4064)
			(end 0.7874 -0.4064)
			(stroke
				(width 0.1524)
				(type default)
			)
			(layer "F.SilkS")
		)
		(fp_line
			(start 0.7874 0.4064)
			(end -0.7874 0.4064)
			(stroke
				(width 0.1524)
				(type default)
			)
			(layer "F.SilkS")
		)
		(fp_line
			(start -0.7874 0.4064)
			(end -0.7874 -0.4064)
			(stroke
				(width 0.1524)
				(type default)
			)
			(layer "F.SilkS")
		)
		(fp_line
			(start -0.12065 -0.305054)
			(end -0.12065 -0.2794)
			(stroke
				(width 0.1)
				(type default)
			)
			(layer "F.Fab")
		)
		(fp_line
			(start -0.67945 -0.305054)
			(end -0.12065 -0.305054)
			(stroke
				(width 0.1)
				(type default)
			)
			(layer "F.Fab")
		)
		(fp_line
			(start 0.67945 -0.3048)
			(end 0.67945 0.3048)
			(stroke
				(width 0.1)
				(type default)
			)
			(layer "F.Fab")
		)
		(fp_line
			(start 0.12065 -0.3048)
			(end 0.67945 -0.3048)
			(stroke
				(width 0.1)
				(type default)
			)
			(layer "F.Fab")
		)
		(fp_line
			(start 0.12065 -0.2794)
			(end 0.12065 -0.3048)
			(stroke
				(width 0.1)
				(type default)
			)
			(layer "F.Fab")
		)
		(fp_line
			(start -0.12065 -0.2794)
			(end 0.12065 -0.2794)
			(stroke
				(width 0.1)
				(type default)
			)
			(layer "F.Fab")
		)
		(fp_line
			(start 0.120396 0.2794)
			(end -0.12065 0.2794)
			(stroke
				(width 0.1)
				(type default)
			)
			(layer "F.Fab")
		)
		(fp_line
			(start -0.12065 0.2794)
			(end -0.12065 0.3048)
			(stroke
				(width 0.1)
				(type default)
			)
			(layer "F.Fab")
		)
		(fp_line
			(start 0.67945 0.3048)
			(end 0.120396 0.3048)
			(stroke
				(width 0.1)
				(type default)
			)
			(layer "F.Fab")
		)
		(fp_line
			(start 0.120396 0.3048)
			(end 0.120396 0.2794)
			(stroke
				(width 0.1)
				(type default)
			)
			(layer "F.Fab")
		)
		(fp_line
			(start -0.12065 0.3048)
			(end -0.67945 0.3048)
			(stroke
				(width 0.1)
				(type default)
			)
			(layer "F.Fab")
		)
		(fp_line
			(start -0.67945 0.3048)
			(end -0.67945 -0.305054)
			(stroke
				(width 0.1)
				(type default)
			)
			(layer "F.Fab")
		)
		(pad "1" smd circle
			(at -0.40005 0 90)
			(size 0 0)
			(layers "F.Cu" "F.Mask" "F.Paste")
			(net "CPU0_THERMTRIP_N")
		)
		(pad "2" smd circle
			(at 0.40005 0 90)
			(size 0 0)
			(layers "F.Cu" "F.Mask" "F.Paste")
			(net "PVDD18_S5_P0")
		)
	)
)
